(kicad_pcb
	(version 20260206)
	(generator "pcbnew")
	(generator_version "10.0")
	(general
		(thickness 1.6)
		(legacy_teardrops no)
	)
	(paper "A4")
	(title_block
		(title "Wiwynn_Tioga_Pass_MB.brd")
		(comment 1 "Tioga Pass / footprint 2254 of 4770 (U5D1), pads 1-79 of 3647")
	)
	(layers
		(0 "F.Cu" signal "TOP")
		(4 "In1.Cu" signal "L2GND")
		(6 "In2.Cu" signal "L3")
		(8 "In3.Cu" signal "L4GND")
		(10 "In4.Cu" signal "L5")
		(12 "In5.Cu" signal "L6GND")
		(14 "In6.Cu" signal "L7VCC")
		(16 "In7.Cu" signal "L8VCC")
		(18 "In8.Cu" signal "L9GND")
		(20 "In9.Cu" signal "L10")
		(22 "In10.Cu" signal "L11GND")
		(24 "In11.Cu" signal "L12")
		(26 "In12.Cu" signal "L13GND")
		(2 "B.Cu" signal "BOTTOM")
		(9 "F.Adhes" user "F.Adhesive")
		(11 "B.Adhes" user "B.Adhesive")
		(13 "F.Paste" user "Package Geometry/Pastemask Top")
		(15 "B.Paste" user "Package Geometry/Pastemask Bottom")
		(5 "F.SilkS" user "Ref Des/Silkscreen Top")
		(7 "B.SilkS" user "Ref Des/Silkscreen Bottom")
		(1 "F.Mask" user "Board Geometry/Soldermask Top")
		(3 "B.Mask" user "Board Geometry/Soldermask Bottom")
		(17 "Dwgs.User" user "User.Drawings")
		(19 "Cmts.User" user "User.Comments")
		(21 "Eco1.User" user "User.Eco1")
		(23 "Eco2.User" user "User.Eco2")
		(25 "Edge.Cuts" user "Board Geometry/Outline")
		(27 "Margin" user)
		(31 "F.CrtYd" user "Package Geometry/Place Bound Top")
		(29 "B.CrtYd" user "Package Geometry/Place Bound Bottom")
		(35 "F.Fab" user "Ref Des/Assembly Top")
		(33 "B.Fab" user "Ref Des/Assembly Bottom")
	)
	(footprint ""
		(layer "F.Cu")
		(at 270.000222 -76.550012 180)
		(property "Reference" "U5D1"
			(at 19.124422 31.601918 0)
			(unlocked yes)
			(layer "F.SilkS")
			(effects
				(font
					(size 0.7874 0.5842)
					(thickness 0.1524)
				)
			)
		)
		(property "Value" ""
			(at 0 0 180)
			(layer "F.Fab")
			(effects
				(font
					(size 1.27 1.27)
				)
			)
		)
		(duplicate_pad_numbers_are_jumpers no)
		(pad "A4" smd custom
			(at -34.675064 -25.103074 45)
			(size 0.10795 0.10795)
			(layers "F.Cu" "F.Mask" "F.Paste")
			(net "TP_CPU0_RSVD_304")
			(options
				(clearance outline)
				(anchor circle)
			)
			(primitives
				(gr_poly
					(pts
						(arc
							(start 0.2159 -0.0381)
							(mid 0 -0.254)
							(end -0.2159 -0.0381)
						)
						(arc
							(start -0.2159 0.0381)
							(mid 0 0.254)
							(end 0.2159 0.0381)
						)
					)
					(width 0)
					(fill yes)
				)
			)
		)
		(pad "A6" smd custom
			(at -32.958024 -25.103074 45)
			(size 0.10795 0.10795)
			(layers "F.Cu" "F.Mask" "F.Paste")
			(net "TP_CPU0_RSVD_303")
			(options
				(clearance outline)
				(anchor circle)
			)
			(primitives
				(gr_poly
					(pts
						(arc
							(start 0.2159 -0.0381)
							(mid 0 -0.254)
							(end -0.2159 -0.0381)
						)
						(arc
							(start -0.2159 0.0381)
							(mid 0 0.254)
							(end 0.2159 0.0381)
						)
					)
					(width 0)
					(fill yes)
				)
			)
		)
		(pad "A8" smd custom
			(at -31.240984 -25.103074)
			(size 0.10795 0.10795)
			(layers "F.Cu" "F.Mask" "F.Paste")
			(net "PVPP_ABC")
			(options
				(clearance outline)
				(anchor circle)
			)
			(primitives
				(gr_poly
					(pts
						(arc
							(start 0.2159 -0.0381)
							(mid 0 -0.254)
							(end -0.2159 -0.0381)
						)
						(arc
							(start -0.2159 0.0381)
							(mid 0 0.254)
							(end 0.2159 0.0381)
						)
					)
					(width 0)
					(fill yes)
				)
			)
		)
		(pad "A10" smd custom
			(at -29.523944 -25.103074)
			(size 0.10795 0.10795)
			(layers "F.Cu" "F.Mask" "F.Paste")
			(net "PVPP_ABC")
			(options
				(clearance outline)
				(anchor circle)
			)
			(primitives
				(gr_poly
					(pts
						(arc
							(start 0.2159 -0.0381)
							(mid 0 -0.254)
							(end -0.2159 -0.0381)
						)
						(arc
							(start -0.2159 0.0381)
							(mid 0 0.254)
							(end 0.2159 0.0381)
						)
					)
					(width 0)
					(fill yes)
				)
			)
		)
		(pad "A12" smd custom
			(at -27.806904 -25.103074)
			(size 0.10795 0.10795)
			(layers "F.Cu" "F.Mask" "F.Paste")
			(net "PVPP_ABC")
			(options
				(clearance outline)
				(anchor circle)
			)
			(primitives
				(gr_poly
					(pts
						(arc
							(start 0.2159 -0.0381)
							(mid 0 -0.254)
							(end -0.2159 -0.0381)
						)
						(arc
							(start -0.2159 0.0381)
							(mid 0 0.254)
							(end 0.2159 0.0381)
						)
					)
					(width 0)
					(fill yes)
				)
			)
		)
		(pad "A14" smd custom
			(at -26.090118 -25.103074)
			(size 0.10795 0.10795)
			(layers "F.Cu" "F.Mask" "F.Paste")
			(net "P1V8_MCP_CPU0")
			(options
				(clearance outline)
				(anchor circle)
			)
			(primitives
				(gr_poly
					(pts
						(arc
							(start 0.2159 -0.0381)
							(mid 0 -0.254)
							(end -0.2159 -0.0381)
						)
						(arc
							(start -0.2159 0.0381)
							(mid 0 0.254)
							(end 0.2159 0.0381)
						)
					)
					(width 0)
					(fill yes)
				)
			)
		)
		(pad "A16" smd custom
			(at -24.373078 -25.103074)
			(size 0.10795 0.10795)
			(layers "F.Cu" "F.Mask" "F.Paste")
			(net "P1V8_MCP_CPU0")
			(options
				(clearance outline)
				(anchor circle)
			)
			(primitives
				(gr_poly
					(pts
						(arc
							(start 0.2159 -0.0381)
							(mid 0 -0.254)
							(end -0.2159 -0.0381)
						)
						(arc
							(start -0.2159 0.0381)
							(mid 0 0.254)
							(end 0.2159 0.0381)
						)
					)
					(width 0)
					(fill yes)
				)
			)
		)
		(pad "A24" smd custom
			(at -17.504918 -25.103074)
			(size 0.10795 0.10795)
			(layers "F.Cu" "F.Mask" "F.Paste")
			(net "TP_CPU0_RSVD_300")
			(options
				(clearance outline)
				(anchor circle)
			)
			(primitives
				(gr_poly
					(pts
						(arc
							(start 0.2159 -0.0381)
							(mid 0 -0.254)
							(end -0.2159 -0.0381)
						)
						(arc
							(start -0.2159 0.0381)
							(mid 0 0.254)
							(end 0.2159 0.0381)
						)
					)
					(width 0)
					(fill yes)
				)
			)
		)
		(pad "A26" smd custom
			(at -15.787878 -25.103074)
			(size 0.10795 0.10795)
			(layers "F.Cu" "F.Mask" "F.Paste")
			(net "GND")
			(options
				(clearance outline)
				(anchor circle)
			)
			(primitives
				(gr_poly
					(pts
						(arc
							(start 0.2159 -0.0381)
							(mid 0 -0.254)
							(end -0.2159 -0.0381)
						)
						(arc
							(start -0.2159 0.0381)
							(mid 0 0.254)
							(end 0.2159 0.0381)
						)
					)
					(width 0)
					(fill yes)
				)
			)
		)
		(pad "A28" smd custom
			(at -14.071092 -25.103074)
			(size 0.10795 0.10795)
			(layers "F.Cu" "F.Mask" "F.Paste")
			(net "M_B_DQS_DN<15>")
			(options
				(clearance outline)
				(anchor circle)
			)
			(primitives
				(gr_poly
					(pts
						(arc
							(start 0.2159 -0.0381)
							(mid 0 -0.254)
							(end -0.2159 -0.0381)
						)
						(arc
							(start -0.2159 0.0381)
							(mid 0 0.254)
							(end 0.2159 0.0381)
						)
					)
					(width 0)
					(fill yes)
				)
			)
		)
		(pad "A30" smd custom
			(at -12.354052 -25.103074)
			(size 0.10795 0.10795)
			(layers "F.Cu" "F.Mask" "F.Paste")
			(net "GND")
			(options
				(clearance outline)
				(anchor circle)
			)
			(primitives
				(gr_poly
					(pts
						(arc
							(start 0.2159 -0.0381)
							(mid 0 -0.254)
							(end -0.2159 -0.0381)
						)
						(arc
							(start -0.2159 0.0381)
							(mid 0 0.254)
							(end 0.2159 0.0381)
						)
					)
					(width 0)
					(fill yes)
				)
			)
		)
		(pad "A32" smd custom
			(at -10.637012 -25.103074)
			(size 0.10795 0.10795)
			(layers "F.Cu" "F.Mask" "F.Paste")
			(net "GND")
			(options
				(clearance outline)
				(anchor circle)
			)
			(primitives
				(gr_poly
					(pts
						(arc
							(start 0.2159 -0.0381)
							(mid 0 -0.254)
							(end -0.2159 -0.0381)
						)
						(arc
							(start -0.2159 0.0381)
							(mid 0 0.254)
							(end 0.2159 0.0381)
						)
					)
					(width 0)
					(fill yes)
				)
			)
		)
		(pad "A34" smd custom
			(at -8.919972 -25.103074)
			(size 0.10795 0.10795)
			(layers "F.Cu" "F.Mask" "F.Paste")
			(net "M_B_DQS_DN<14>")
			(options
				(clearance outline)
				(anchor circle)
			)
			(primitives
				(gr_poly
					(pts
						(arc
							(start 0.2159 -0.0381)
							(mid 0 -0.254)
							(end -0.2159 -0.0381)
						)
						(arc
							(start -0.2159 0.0381)
							(mid 0 0.254)
							(end 0.2159 0.0381)
						)
					)
					(width 0)
					(fill yes)
				)
			)
		)
		(pad "A36" smd custom
			(at -7.202932 -25.103074)
			(size 0.10795 0.10795)
			(layers "F.Cu" "F.Mask" "F.Paste")
			(net "GND")
			(options
				(clearance outline)
				(anchor circle)
			)
			(primitives
				(gr_poly
					(pts
						(arc
							(start 0.2159 -0.0381)
							(mid 0 -0.254)
							(end -0.2159 -0.0381)
						)
						(arc
							(start -0.2159 0.0381)
							(mid 0 0.254)
							(end 0.2159 0.0381)
						)
					)
					(width 0)
					(fill yes)
				)
			)
		)
		(pad "A38" smd custom
			(at -5.485892 -25.103074)
			(size 0.10795 0.10795)
			(layers "F.Cu" "F.Mask" "F.Paste")
			(net "GND")
			(options
				(clearance outline)
				(anchor circle)
			)
			(primitives
				(gr_poly
					(pts
						(arc
							(start 0.2159 -0.0381)
							(mid 0 -0.254)
							(end -0.2159 -0.0381)
						)
						(arc
							(start -0.2159 0.0381)
							(mid 0 0.254)
							(end 0.2159 0.0381)
						)
					)
					(width 0)
					(fill yes)
				)
			)
		)
		(pad "A40" smd custom
			(at -3.769106 -25.103074)
			(size 0.10795 0.10795)
			(layers "F.Cu" "F.Mask" "F.Paste")
			(net "M_A_DQS_DN<13>")
			(options
				(clearance outline)
				(anchor circle)
			)
			(primitives
				(gr_poly
					(pts
						(arc
							(start 0.2159 -0.0381)
							(mid 0 -0.254)
							(end -0.2159 -0.0381)
						)
						(arc
							(start -0.2159 0.0381)
							(mid 0 0.254)
							(end 0.2159 0.0381)
						)
					)
					(width 0)
					(fill yes)
				)
			)
		)
		(pad "A42" smd custom
			(at -2.052066 -25.103074 315)
			(size 0.10795 0.10795)
			(layers "F.Cu" "F.Mask" "F.Paste")
			(net "GND")
			(options
				(clearance outline)
				(anchor circle)
			)
			(primitives
				(gr_poly
					(pts
						(arc
							(start 0.2159 -0.0381)
							(mid 0 -0.254)
							(end -0.2159 -0.0381)
						)
						(arc
							(start -0.2159 0.0381)
							(mid 0 0.254)
							(end 0.2159 0.0381)
						)
					)
					(width 0)
					(fill yes)
				)
			)
		)
		(pad "AA2" smd circle
			(at -36.392104 -15.197074)
			(size 0.4318 0.4318)
			(layers "F.Cu" "F.Mask" "F.Paste")
			(net "UPI_CPU0_CPU1_P0P0_DP<15>")
		)
		(pad "AA4" smd circle
			(at -34.675064 -15.197074)
			(size 0.4318 0.4318)
			(layers "F.Cu" "F.Mask" "F.Paste")
			(net "GND")
		)
		(pad "AA6" smd circle
			(at -32.958024 -15.197074)
			(size 0.4318 0.4318)
			(layers "F.Cu" "F.Mask" "F.Paste")
			(net "UPI_CPU1_CPU0_P0P0_DP<17>")
		)
		(pad "AA8" smd circle
			(at -31.240984 -15.197074)
			(size 0.4318 0.4318)
			(layers "F.Cu" "F.Mask" "F.Paste")
			(net "UPI_CPU1_CPU0_P0P0_DN<18>")
		)
		(pad "AA10" smd circle
			(at -29.523944 -15.197074)
			(size 0.4318 0.4318)
			(layers "F.Cu" "F.Mask" "F.Paste")
			(net "PVCCIO_CPU0")
		)
		(pad "AA12" smd circle
			(at -27.806904 -15.197074)
			(size 0.4318 0.4318)
			(layers "F.Cu" "F.Mask" "F.Paste")
			(net "TP_XDP_CPU0_OBSDATA_A2_MBP4_N")
		)
		(pad "AA14" smd circle
			(at -26.090118 -15.197074)
			(size 0.4318 0.4318)
			(layers "F.Cu" "F.Mask" "F.Paste")
			(net "XDP_CPU_TCK0")
		)
		(pad "AA16" smd circle
			(at -24.373078 -15.197074)
			(size 0.4318 0.4318)
			(layers "F.Cu" "F.Mask" "F.Paste")
			(net "GND")
		)
		(pad "AA18" smd circle
			(at -22.656038 -15.197074)
			(size 0.4318 0.4318)
			(layers "F.Cu" "F.Mask" "F.Paste")
			(net "GND")
		)
		(pad "AA20" smd circle
			(at -20.938998 -15.197074)
			(size 0.4318 0.4318)
			(layers "F.Cu" "F.Mask" "F.Paste")
			(net "UPI_CPU1_CPU0_P1P1_DP<0>")
		)
		(pad "AA22" smd circle
			(at -19.221958 -15.197074)
			(size 0.4318 0.4318)
			(layers "F.Cu" "F.Mask" "F.Paste")
			(net "GND")
		)
		(pad "AA24" smd circle
			(at -17.504918 -15.197074)
			(size 0.4318 0.4318)
			(layers "F.Cu" "F.Mask" "F.Paste")
			(net "GND")
		)
		(pad "AA26" smd circle
			(at -15.787878 -15.197074)
			(size 0.4318 0.4318)
			(layers "F.Cu" "F.Mask" "F.Paste")
			(net "M_B_DQ<63>")
		)
		(pad "AA28" smd circle
			(at -14.071092 -15.197074)
			(size 0.4318 0.4318)
			(layers "F.Cu" "F.Mask" "F.Paste")
			(net "M_B_DQ<57>")
		)
		(pad "AA30" smd circle
			(at -12.354052 -15.197074)
			(size 0.4318 0.4318)
			(layers "F.Cu" "F.Mask" "F.Paste")
			(net "GND")
		)
		(pad "AA32" smd circle
			(at -10.637012 -15.197074)
			(size 0.4318 0.4318)
			(layers "F.Cu" "F.Mask" "F.Paste")
			(net "M_C_DQ<47>")
		)
		(pad "AA34" smd circle
			(at -8.919972 -15.197074)
			(size 0.4318 0.4318)
			(layers "F.Cu" "F.Mask" "F.Paste")
			(net "M_C_DQ<41>")
		)
		(pad "AA36" smd circle
			(at -7.202932 -15.197074)
			(size 0.4318 0.4318)
			(layers "F.Cu" "F.Mask" "F.Paste")
			(net "GND")
		)
		(pad "AA38" smd circle
			(at -5.485892 -15.197074)
			(size 0.4318 0.4318)
			(layers "F.Cu" "F.Mask" "F.Paste")
			(net "M_C_DQ<39>")
		)
		(pad "AA40" smd circle
			(at -3.769106 -15.197074)
			(size 0.4318 0.4318)
			(layers "F.Cu" "F.Mask" "F.Paste")
			(net "M_C_DQ<33>")
		)
		(pad "AA42" smd circle
			(at -2.052066 -15.197074)
			(size 0.4318 0.4318)
			(layers "F.Cu" "F.Mask" "F.Paste")
			(net "GND")
		)
		(pad "AA46" smd circle
			(at 2.910586 -16.997172)
			(size 0.4318 0.4318)
			(layers "F.Cu" "F.Mask" "F.Paste")
			(net "M_C_CS_N<3>")
		)
		(pad "AA48" smd circle
			(at 4.627626 -16.997172)
			(size 0.4318 0.4318)
			(layers "F.Cu" "F.Mask" "F.Paste")
			(net "M_C_ODT<1>")
		)
		(pad "AA50" smd circle
			(at 6.344412 -16.997172)
			(size 0.4318 0.4318)
			(layers "F.Cu" "F.Mask" "F.Paste")
			(net "M_C_ODT<0>")
		)
		(pad "AA52" smd circle
			(at 8.061452 -16.997172)
			(size 0.4318 0.4318)
			(layers "F.Cu" "F.Mask" "F.Paste")
			(net "M_C_MA<16>")
		)
		(pad "AA54" smd circle
			(at 9.778492 -16.997172)
			(size 0.4318 0.4318)
			(layers "F.Cu" "F.Mask" "F.Paste")
			(net "M_C_CLK_DN<0>")
		)
		(pad "AA56" smd circle
			(at 11.495532 -16.997172)
			(size 0.4318 0.4318)
			(layers "F.Cu" "F.Mask" "F.Paste")
			(net "M_C_CLK_DN<2>")
		)
		(pad "AA58" smd circle
			(at 13.212572 -16.997172)
			(size 0.4318 0.4318)
			(layers "F.Cu" "F.Mask" "F.Paste")
			(net "M_C_MA<4>")
		)
		(pad "AA60" smd circle
			(at 14.929612 -16.997172)
			(size 0.4318 0.4318)
			(layers "F.Cu" "F.Mask" "F.Paste")
			(net "M_C_BG<0>")
		)
		(pad "AA62" smd circle
			(at 16.646398 -16.997172)
			(size 0.4318 0.4318)
			(layers "F.Cu" "F.Mask" "F.Paste")
			(net "M_C_CKE<0>")
		)
		(pad "AA64" smd circle
			(at 18.363438 -16.997172)
			(size 0.4318 0.4318)
			(layers "F.Cu" "F.Mask" "F.Paste")
			(net "GND")
		)
		(pad "AA66" smd circle
			(at 20.080478 -16.997172)
			(size 0.4318 0.4318)
			(layers "F.Cu" "F.Mask" "F.Paste")
			(net "GND")
		)
		(pad "AA68" smd circle
			(at 21.797518 -16.997172)
			(size 0.4318 0.4318)
			(layers "F.Cu" "F.Mask" "F.Paste")
			(net "GND")
		)
		(pad "AA70" smd circle
			(at 23.514558 -16.997172)
			(size 0.4318 0.4318)
			(layers "F.Cu" "F.Mask" "F.Paste")
			(net "M_C_DQ<17>")
		)
		(pad "AA72" smd circle
			(at 25.231598 -16.997172)
			(size 0.4318 0.4318)
			(layers "F.Cu" "F.Mask" "F.Paste")
			(net "M_C_DQ<20>")
		)
		(pad "AA74" smd circle
			(at 26.948384 -16.997172)
			(size 0.4318 0.4318)
			(layers "F.Cu" "F.Mask" "F.Paste")
			(net "M_C_DQS_DN<1>")
		)
		(pad "AA76" smd circle
			(at 28.665424 -16.997172)
			(size 0.4318 0.4318)
			(layers "F.Cu" "F.Mask" "F.Paste")
			(net "GND")
		)
		(pad "AA78" smd circle
			(at 30.382464 -16.997172)
			(size 0.4318 0.4318)
			(layers "F.Cu" "F.Mask" "F.Paste")
			(net "GND")
		)
		(pad "AA80" smd circle
			(at 32.099504 -16.997172)
			(size 0.4318 0.4318)
			(layers "F.Cu" "F.Mask" "F.Paste")
			(net "GND")
		)
		(pad "AA82" smd circle
			(at 33.816544 -16.997172)
			(size 0.4318 0.4318)
			(layers "F.Cu" "F.Mask" "F.Paste")
			(net "GND")
		)
		(pad "AA84" smd circle
			(at 35.533584 -16.997172)
			(size 0.4318 0.4318)
			(layers "F.Cu" "F.Mask" "F.Paste")
			(net "M_A_DQ<13>")
		)
		(pad "AA86" smd custom
			(at 37.250624 -16.997172 270)
			(size 0.10795 0.10795)
			(layers "F.Cu" "F.Mask" "F.Paste")
			(net "M_A_DQ<12>")
			(options
				(clearance outline)
				(anchor circle)
			)
			(primitives
				(gr_poly
					(pts
						(arc
							(start 0.2159 -0.0381)
							(mid 0 -0.254)
							(end -0.2159 -0.0381)
						)
						(arc
							(start -0.2159 0.0381)
							(mid 0 0.254)
							(end 0.2159 0.0381)
						)
					)
					(width 0)
					(fill yes)
				)
			)
		)
		(pad "AB1" smd custom
			(at -37.250624 -14.702028 90)
			(size 0.10795 0.10795)
			(layers "F.Cu" "F.Mask" "F.Paste")
			(net "GND")
			(options
				(clearance outline)
				(anchor circle)
			)
			(primitives
				(gr_poly
					(pts
						(arc
							(start 0.2159 -0.0381)
							(mid 0 -0.254)
							(end -0.2159 -0.0381)
						)
						(arc
							(start -0.2159 0.0381)
							(mid 0 0.254)
							(end 0.2159 0.0381)
						)
					)
					(width 0)
					(fill yes)
				)
			)
		)
		(pad "AB3" smd circle
			(at -35.533584 -14.702028)
			(size 0.4318 0.4318)
			(layers "F.Cu" "F.Mask" "F.Paste")
			(net "UPI_CPU0_CPU1_P0P0_DN<15>")
		)
		(pad "AB5" smd circle
			(at -33.816544 -14.702028)
			(size 0.4318 0.4318)
			(layers "F.Cu" "F.Mask" "F.Paste")
			(net "GND")
		)
		(pad "AB7" smd circle
			(at -32.099504 -14.702028)
			(size 0.4318 0.4318)
			(layers "F.Cu" "F.Mask" "F.Paste")
			(net "UPI_CPU1_CPU0_P0P0_DN<17>")
		)
		(pad "AB9" smd circle
			(at -30.382464 -14.702028)
			(size 0.4318 0.4318)
			(layers "F.Cu" "F.Mask" "F.Paste")
			(net "UPI_CPU1_CPU0_P0P0_DP<19>")
		)
		(pad "AB11" smd circle
			(at -28.665424 -14.702028)
			(size 0.4318 0.4318)
			(layers "F.Cu" "F.Mask" "F.Paste")
			(net "GND")
		)
		(pad "AB13" smd circle
			(at -26.948384 -14.702028)
			(size 0.4318 0.4318)
			(layers "F.Cu" "F.Mask" "F.Paste")
			(net "FM_CPU0_SKTOCC_LVT3_N")
		)
		(pad "AB15" smd circle
			(at -25.231598 -14.702028)
			(size 0.4318 0.4318)
			(layers "F.Cu" "F.Mask" "F.Paste")
			(net "H_CPU0_THERMTRIP_G_N")
		)
		(pad "AB17" smd circle
			(at -23.514558 -14.702028)
			(size 0.4318 0.4318)
			(layers "F.Cu" "F.Mask" "F.Paste")
			(net "TP_CPU0_PROCDIS_G_N")
		)
		(pad "AB19" smd circle
			(at -21.797518 -14.702028)
			(size 0.4318 0.4318)
			(layers "F.Cu" "F.Mask" "F.Paste")
			(net "UPI_CPU1_CPU0_P1P1_DN<0>")
		)
		(pad "AB21" smd circle
			(at -20.080478 -14.702028)
			(size 0.4318 0.4318)
			(layers "F.Cu" "F.Mask" "F.Paste")
			(net "GND")
		)
		(pad "AB23" smd circle
			(at -18.363438 -14.702028)
			(size 0.4318 0.4318)
			(layers "F.Cu" "F.Mask" "F.Paste")
			(net "GND")
		)
		(pad "AB25" smd circle
			(at -16.646398 -14.702028)
			(size 0.4318 0.4318)
			(layers "F.Cu" "F.Mask" "F.Paste")
			(net "GND")
		)
		(pad "AB27" smd circle
			(at -14.929612 -14.702028)
			(size 0.4318 0.4318)
			(layers "F.Cu" "F.Mask" "F.Paste")
			(net "M_B_DQS_DN<7>")
		)
		(pad "AB29" smd circle
			(at -13.212572 -14.702028)
			(size 0.4318 0.4318)
			(layers "F.Cu" "F.Mask" "F.Paste")
			(net "GND")
		)
		(pad "AB31" smd circle
			(at -11.495532 -14.702028)
			(size 0.4318 0.4318)
			(layers "F.Cu" "F.Mask" "F.Paste")
			(net "GND")
		)
		(pad "AB33" smd circle
			(at -9.778492 -14.702028)
			(size 0.4318 0.4318)
			(layers "F.Cu" "F.Mask" "F.Paste")
			(net "M_C_DQS_DN<5>")
		)
		(pad "AB35" smd circle
			(at -8.061452 -14.702028)
			(size 0.4318 0.4318)
			(layers "F.Cu" "F.Mask" "F.Paste")
			(net "GND")
		)
		(pad "AB37" smd circle
			(at -6.344412 -14.702028)
			(size 0.4318 0.4318)
			(layers "F.Cu" "F.Mask" "F.Paste")
			(net "GND")
		)
		(pad "AB39" smd circle
			(at -4.627626 -14.702028)
			(size 0.4318 0.4318)
			(layers "F.Cu" "F.Mask" "F.Paste")
			(net "M_C_DQS_DN<4>")
		)
	)
)
